# BASEBOARD_FAB2 (Tioga Pass) — schematic netlist excerpt (pin names and nets, part order shuffled) for the footprints in the layout excerpt that follows; sources: Cadence DE-HDL packaged netlist, KiCad conversion of Wiwynn_Tioga_Pass_MB.brd

J9L1  SCONN288_H44441003  SCONN  pkg PIP  page 88
  \12v\(1)  = P12V_NVDIMM_KLM
  VSS(93)  = GND
  DQ(4)  = M_M_DQ<4>
  VSS(92)  = GND
  DQ(0)  = M_M_DQ<0>
  VSS(91)  = GND
  DQS9P  = M_M_DQS_DP<9>
  DQS9N  = M_M_DQS_DN<9>
  VSS(90)  = GND
  DQ(6)  = M_M_DQ<6>
  VSS(89)  = GND
  DQ(2)  = M_M_DQ<2>
  VSS(88)  = GND
  DQ(12)  = M_M_DQ<12>
  VSS(87)  = GND
  DQ(8)  = M_M_DQ<8>
  VSS(86)  = GND
  DQS10P  = M_M_DQS_DP<10>
  DQS10N  = M_M_DQS_DN<10>
  VSS(85)  = GND
  DQ(14)  = M_M_DQ<14>
  VSS(84)  = GND
  DQ(10)  = M_M_DQ<10>
  VSS(83)  = GND
  DQ(20)  = M_M_DQ<20>
  VSS(82)  = GND
  DQ(16)  = M_M_DQ<16>
  VSS(81)  = GND
  DQS11P  = M_M_DQS_DP<11>
  DQS11N  = M_M_DQS_DN<11>
  VSS(80)  = GND
  DQ(22)  = M_M_DQ<22>
  VSS(79)  = GND
  DQ(18)  = M_M_DQ<18>
  VSS(78)  = GND
  DQ(28)  = M_M_DQ<28>
  VSS(77)  = GND
  DQ(24)  = M_M_DQ<24>
  VSS(76)  = GND
  DQS12P  = M_M_DQS_DP<12>
  DQS12N  = M_M_DQS_DN<12>
  VSS(75)  = GND
  DQ(30)  = M_M_DQ<30>
  VSS(74)  = GND
  DQ(26)  = M_M_DQ<26>
  VSS(73)  = GND
  CB(4)  = M_M_ECC<4>
  VSS(72)  = GND
  CB(0)  = M_M_ECC<0>
  VSS(71)  = GND
  DQS17P  = M_M_DQS_DP<17>
  DQS17N  = M_M_DQS_DN<17>
  VSS(70)  = GND
  CB(6)  = M_M_ECC<6>
  VSS(69)  = GND
  CB(2)  = M_M_ECC<2>
  VSS(68)  = GND
  RESET_N  = M_KLM_RST_N
  VDD(25)  = PVDDQ_KLM
  CKE(0)  = M_M_CKE<2>
  VDD(24)  = PVDDQ_KLM
  ACT_N  = M_M_ACT_N
  BG(0)  = M_M_BG<0>
  VDD(23)  = PVDDQ_KLM
  A12  = M_M_MA<12>
  A9  = M_M_MA<9>
  VDD(22)  = PVDDQ_KLM
  A8  = M_M_MA<8>
  A6  = M_M_MA<6>
  VDD(21)  = PVDDQ_KLM
  A3  = M_M_MA<3>
  A1  = M_M_MA<1>
  VDD(20)  = PVDDQ_KLM
  CK0P  = M_M_CLK_DP<2>
  CK0N  = M_M_CLK_DN<2>
  VDD(19)  = PVDDQ_KLM
  VTT(1)  = PVTT_KLM
  EVENT_N  = FM_DIMM_EVENT_COD_N
  A0  = M_M_MA<0>
  VDD(18)  = PVDDQ_KLM
  BA(0)  = M_M_BA<0>
  A16_RAS_N  = M_M_MA<16>
  VDD(17)  = PVDDQ_KLM
  S0_N  = M_M_CS_N<4>
  VDD(16)  = PVDDQ_KLM
  A15_CAS_N  = M_M_MA<15>
  ODT(0)  = M_M_ODT<2>
  VDD(15)  = PVDDQ_KLM
  S1_N  = M_M_CS_N<5>
  VDD(14)  = PVDDQ_KLM
  ODT(1)  = M_M_ODT<3>
  VDD(13)  = PVDDQ_KLM
  S2_N_C(0)  = M_M_CS_N<6>
  VSS(67)  = GND
  DQ(36)  = M_M_DQ<36>
  VSS(66)  = GND
  DQ(32)  = M_M_DQ<32>
  VSS(65)  = GND
  DQS13P  = M_M_DQS_DP<13>
  DQS13N  = M_M_DQS_DN<13>
  VSS(64)  = GND
  DQ(38)  = M_M_DQ<38>
  VSS(63)  = GND
  DQ(34)  = M_M_DQ<34>
  VSS(62)  = GND
  DQ(44)  = M_M_DQ<44>
  VSS(61)  = GND
  DQ(40)  = M_M_DQ<40>
  VSS(60)  = GND
  DQS14P  = M_M_DQS_DP<14>
  DQS14N  = M_M_DQS_DN<14>
  VSS(59)  = GND
  DQ(46)  = M_M_DQ<46>
  VSS(58)  = GND
  DQ(42)  = M_M_DQ<42>
  VSS(57)  = GND
  DQ(52)  = M_M_DQ<52>
  VSS(56)  = GND
  DQ(48)  = M_M_DQ<48>
  VSS(55)  = GND
  DQS15P  = M_M_DQS_DP<15>
  DQS15N  = M_M_DQS_DN<15>
  VSS(54)  = GND
  DQ(54)  = M_M_DQ<54>
  VSS(53)  = GND
  DQ(50)  = M_M_DQ<50>
  VSS(52)  = GND
  DQ(60)  = M_M_DQ<60>
  VSS(51)  = GND
  DQ(56)  = M_M_DQ<56>
  VSS(50)  = GND
  DQS16P  = M_M_DQS_DP<16>
  DQS16N  = M_M_DQS_DN<16>
  VSS(49)  = GND
  DQ(62)  = M_M_DQ<62>
  VSS(48)  = GND
  DQ(58)  = M_M_DQ<58>
  VSS(47)  = GND
  SA(0)  = PVPP_KLM
  SA(1)  = GND
  SCL  = SMB_DDR_KLM_VPP_SCL
  VPP(4)  = PVPP_KLM
  VPP(3)  = PVPP_KLM
  RFU(2)  = TP_CH_M_DIMM_M1_RFU_2
  \12v\(0)  = P12V_NVDIMM_KLM
  VREFCA  = M_M_VREF
  VSS(46)  = GND
  DQ(5)  = M_M_DQ<5>
  VSS(45)  = GND
  DQ(1)  = M_M_DQ<1>
  VSS(44)  = GND
  DQS0N  = M_M_DQS_DN<0>
  DQS0P  = M_M_DQS_DP<0>
  VSS(43)  = GND
  DQ(7)  = M_M_DQ<7>
  VSS(42)  = GND
  DQ(3)  = M_M_DQ<3>
  VSS(41)  = GND
  DQ(13)  = M_M_DQ<13>
  VSS(40)  = GND
  DQ(9)  = M_M_DQ<9>
  VSS(39)  = GND
  DQS1N  = M_M_DQS_DN<1>
  DQS1P  = M_M_DQS_DP<1>
  VSS(38)  = GND
  DQ(15)  = M_M_DQ<15>
  VSS(37)  = GND
  DQ(11)  = M_M_DQ<11>
  VSS(36)  = GND
  DQ(21)  = M_M_DQ<21>
  VSS(35)  = GND
  DQ(17)  = M_M_DQ<17>
  VSS(34)  = GND
  DQS2N  = M_M_DQS_DN<2>
  DQS2P  = M_M_DQS_DP<2>
  VSS(33)  = GND
  DQ(23)  = M_M_DQ<23>
  VSS(32)  = GND
  DQ(19)  = M_M_DQ<19>
  VSS(31)  = GND
  DQ(29)  = M_M_DQ<29>
  VSS(30)  = GND
  DQ(25)  = M_M_DQ<25>
  VSS(29)  = GND
  DQS3N  = M_M_DQS_DN<3>
  DQS3P  = M_M_DQS_DP<3>
  VSS(28)  = GND
  DQ(31)  = M_M_DQ<31>
  VSS(27)  = GND
  DQ(27)  = M_M_DQ<27>
  VSS(26)  = GND
  CB(5)  = M_M_ECC<5>
  VSS(25)  = GND
  CB(1)  = M_M_ECC<1>
  VSS(24)  = GND
  DQS8N  = M_M_DQS_DN<8>
  DQS8P  = M_M_DQS_DP<8>
  VSS(23)  = GND
  CB(7)  = M_M_ECC<7>
  VSS(22)  = GND
  CB(3)  = M_M_ECC<3>
  VSS(21)  = GND
  CKE(1)  = M_M_CKE<3>
  VDD(12)  = PVDDQ_KLM
  RFU(0)  = TP_CH_M_DIMM_M1_RFU_0
  VDD(11)  = PVDDQ_KLM
  BG(1)  = M_M_BG<1>
  ALERT_N  = M_M_ALERT_N
  VDD(10)  = PVDDQ_KLM
  A11  = M_M_MA<11>
  A7  = M_M_MA<7>
  VDD(9)  = PVDDQ_KLM
  A5  = M_M_MA<5>
  A4  = M_M_MA<4>
  VDD(8)  = PVDDQ_KLM
  A2  = M_M_MA<2>
  VDD(7)  = PVDDQ_KLM
  CK1P  = M_M_CLK_DP<3>
  CK1N  = M_M_CLK_DN<3>
  VDD(6)  = PVDDQ_KLM
  VTT(0)  = PVTT_KLM
  PAR  = M_M_PAR
  VDD(5)  = PVDDQ_KLM
  BA(1)  = M_M_BA<1>
  A10  = M_M_MA<10>
  VDD(4)  = PVDDQ_KLM
  RFU(1)  = TP_CH_M_DIMM_M1_RFU_1
  A14_WE_N  = M_M_MA<14>
  VDD(3)  = PVDDQ_KLM
  SAVE_N_NC  = FM_ADR_COMPLETE_KLM_N
  VDD(2)  = PVDDQ_KLM
  A13  = M_M_MA<13>
  VDD(1)  = PVDDQ_KLM
  A17  = M_M_MA<17>
  C(2)  = M_M_C<2>
  VDD(0)  = PVDDQ_KLM
  S3_N_C(1)  = M_M_CS_N<7>
  SA(2)  = PVPP_KLM
  VSS(20)  = GND
  DQ(37)  = M_M_DQ<37>
  VSS(19)  = GND
  DQ(33)  = M_M_DQ<33>
  VSS(18)  = GND
  DQS4N  = M_M_DQS_DN<4>
  DQS4P  = M_M_DQS_DP<4>
  VSS(17)  = GND
  DQ(39)  = M_M_DQ<39>
  VSS(16)  = GND
  DQ(35)  = M_M_DQ<35>
  VSS(15)  = GND
  DQ(45)  = M_M_DQ<45>
  VSS(14)  = GND
  DQ(41)  = M_M_DQ<41>
  VSS(13)  = GND
  DQS5N  = M_M_DQS_DN<5>
  DQS5P  = M_M_DQS_DP<5>
  VSS(12)  = GND
  DQ(47)  = M_M_DQ<47>
  VSS(11)  = GND
  DQ(43)  = M_M_DQ<43>
  VSS(10)  = GND
  DQ(53)  = M_M_DQ<53>
  VSS(9)  = GND
  DQ(49)  = M_M_DQ<49>
  VSS(8)  = GND
  DQS6N  = M_M_DQS_DN<6>
  DQS6P  = M_M_DQS_DP<6>
  VSS(7)  = GND
  DQ(55)  = M_M_DQ<55>
  VSS(6)  = GND
  DQ(51)  = M_M_DQ<51>
  VSS(5)  = GND
  DQ(61)  = M_M_DQ<61>
  VSS(4)  = GND
  DQ(57)  = M_M_DQ<57>
  VSS(3)  = GND
  DQS7N  = M_M_DQS_DN<7>
  DQS7P  = M_M_DQS_DP<7>
  VSS(2)  = GND
  DQ(63)  = M_M_DQ<63>
  VSS(1)  = GND
  DQ(59)  = M_M_DQ<59>
  VSS(0)  = GND
  VDDSPD  = PVPP_KLM
  SDA  = SMB_DDR_KLM_VPP_SDA
  VPP(1)  = PVPP_KLM
  VPP(0)  = PVPP_KLM
  VPP(2)  = PVPP_KLM

(kicad_pcb
	(version 20260206)
	(generator "pcbnew")
	(generator_version "10.0")
	(general
		(thickness 1.6)
		(legacy_teardrops no)
	)
	(paper "A4")
	(title_block
		(title "Wiwynn_Tioga_Pass_MB.brd")
		(comment 1 "Tioga Pass / footprint 2717 of 4770 (J9L1), pads 51-100 of 291")
	)
	(layers
		(0 "F.Cu" signal "TOP")
		(4 "In1.Cu" signal "L2GND")
		(6 "In2.Cu" signal "L3")
		(8 "In3.Cu" signal "L4GND")
		(10 "In4.Cu" signal "L5")
		(12 "In5.Cu" signal "L6GND")
		(14 "In6.Cu" signal "L7VCC")
		(16 "In7.Cu" signal "L8VCC")
		(18 "In8.Cu" signal "L9GND")
		(20 "In9.Cu" signal "L10")
		(22 "In10.Cu" signal "L11GND")
		(24 "In11.Cu" signal "L12")
		(26 "In12.Cu" signal "L13GND")
		(2 "B.Cu" signal "BOTTOM")
		(9 "F.Adhes" user "F.Adhesive")
		(11 "B.Adhes" user "B.Adhesive")
		(13 "F.Paste" user "Package Geometry/Pastemask Top")
		(15 "B.Paste" user "Package Geometry/Pastemask Bottom")
		(5 "F.SilkS" user "Ref Des/Silkscreen Top")
		(7 "B.SilkS" user "Ref Des/Silkscreen Bottom")
		(1 "F.Mask" user "Board Geometry/Soldermask Top")
		(3 "B.Mask" user "Board Geometry/Soldermask Bottom")
		(17 "Dwgs.User" user "User.Drawings")
		(19 "Cmts.User" user "User.Comments")
		(21 "Eco1.User" user "User.Eco1")
		(23 "Eco2.User" user "User.Eco2")
		(25 "Edge.Cuts" user "Board Geometry/Outline")
		(27 "Margin" user)
		(31 "F.CrtYd" user "Package Geometry/Place Bound Top")
		(29 "B.CrtYd" user "Package Geometry/Place Bound Bottom")
		(35 "F.Fab" user "Ref Des/Assembly Top")
		(33 "B.Fab" user "Ref Des/Assembly Bottom")
	)
	(footprint ""
		(layer "B.Cu")
		(at 29.699458 -152.078436 90)
		(property "Reference" "J9L1"
			(at 2.200148 37.737542 0)
			(unlocked yes)
			(layer "B.SilkS")
			(effects
				(font
					(size 0.7874 0.5842)
					(thickness 0.1524)
				)
				(justify left mirror)
			)
		)
		(property "Value" ""
			(at 0 0 90)
			(layer "B.Fab")
			(effects
				(font
					(size 1.27 1.27)
				)
				(justify mirror)
			)
		)
		(duplicate_pad_numbers_are_jumpers no)
		(pad "48" smd rect
			(at 0 39.949882 270)
			(size 1.8034 0.508)
			(layers "B.Cu" "B.Mask" "B.Paste")
			(net "GND")
		)
		(pad "49" smd rect
			(at 0 40.80002 270)
			(size 1.8034 0.508)
			(layers "B.Cu" "B.Mask" "B.Paste")
			(net "M_M_ECC<0>")
		)
		(pad "50" smd rect
			(at 0 41.649904 270)
			(size 1.8034 0.508)
			(layers "B.Cu" "B.Mask" "B.Paste")
			(net "GND")
		)
		(pad "51" smd rect
			(at 0 42.500042 270)
			(size 1.8034 0.508)
			(layers "B.Cu" "B.Mask" "B.Paste")
			(net "M_M_DQS_DP<17>")
		)
		(pad "52" smd rect
			(at 0 43.349926 270)
			(size 1.8034 0.508)
			(layers "B.Cu" "B.Mask" "B.Paste")
			(net "M_M_DQS_DN<17>")
		)
		(pad "53" smd rect
			(at 0 44.200064 270)
			(size 1.8034 0.508)
			(layers "B.Cu" "B.Mask" "B.Paste")
			(net "GND")
		)
		(pad "54" smd rect
			(at 0 45.049948 270)
			(size 1.8034 0.508)
			(layers "B.Cu" "B.Mask" "B.Paste")
			(net "M_M_ECC<6>")
		)
		(pad "55" smd rect
			(at 0 45.900086 270)
			(size 1.8034 0.508)
			(layers "B.Cu" "B.Mask" "B.Paste")
			(net "GND")
		)
		(pad "56" smd rect
			(at 0 46.74997 270)
			(size 1.8034 0.508)
			(layers "B.Cu" "B.Mask" "B.Paste")
			(net "M_M_ECC<2>")
		)
		(pad "57" smd rect
			(at 0 47.600108 270)
			(size 1.8034 0.508)
			(layers "B.Cu" "B.Mask" "B.Paste")
			(net "GND")
		)
		(pad "58" smd rect
			(at 0 48.449992 270)
			(size 1.8034 0.508)
			(layers "B.Cu" "B.Mask" "B.Paste")
			(net "M_KLM_RST_N")
		)
		(pad "59" smd rect
			(at 0 49.299876 270)
			(size 1.8034 0.508)
			(layers "B.Cu" "B.Mask" "B.Paste")
			(net "PVDDQ_KLM")
		)
		(pad "60" smd rect
			(at 0 50.150014 270)
			(size 1.8034 0.508)
			(layers "B.Cu" "B.Mask" "B.Paste")
			(net "M_M_CKE<2>")
		)
		(pad "61" smd rect
			(at 0 50.999898 270)
			(size 1.8034 0.508)
			(layers "B.Cu" "B.Mask" "B.Paste")
			(net "PVDDQ_KLM")
		)
		(pad "62" smd rect
			(at 0 51.850036 270)
			(size 1.8034 0.508)
			(layers "B.Cu" "B.Mask" "B.Paste")
			(net "M_M_ACT_N")
		)
		(pad "63" smd rect
			(at 0 52.69992 270)
			(size 1.8034 0.508)
			(layers "B.Cu" "B.Mask" "B.Paste")
			(net "M_M_BG<0>")
		)
		(pad "64" smd rect
			(at 0 53.550058 270)
			(size 1.8034 0.508)
			(layers "B.Cu" "B.Mask" "B.Paste")
			(net "PVDDQ_KLM")
		)
		(pad "65" smd rect
			(at 0 54.399942 270)
			(size 1.8034 0.508)
			(layers "B.Cu" "B.Mask" "B.Paste")
			(net "M_M_MA<12>")
		)
		(pad "66" smd rect
			(at 0 55.25008 270)
			(size 1.8034 0.508)
			(layers "B.Cu" "B.Mask" "B.Paste")
			(net "M_M_MA<9>")
		)
		(pad "67" smd rect
			(at 0 56.099964 270)
			(size 1.8034 0.508)
			(layers "B.Cu" "B.Mask" "B.Paste")
			(net "PVDDQ_KLM")
		)
		(pad "68" smd rect
			(at 0 56.950102 270)
			(size 1.8034 0.508)
			(layers "B.Cu" "B.Mask" "B.Paste")
			(net "M_M_MA<8>")
		)
		(pad "69" smd rect
			(at 0 57.799986 270)
			(size 1.8034 0.508)
			(layers "B.Cu" "B.Mask" "B.Paste")
			(net "M_M_MA<6>")
		)
		(pad "70" smd rect
			(at 0 58.650124 270)
			(size 1.8034 0.508)
			(layers "B.Cu" "B.Mask" "B.Paste")
			(net "PVDDQ_KLM")
		)
		(pad "71" smd rect
			(at 0 59.500008 270)
			(size 1.8034 0.508)
			(layers "B.Cu" "B.Mask" "B.Paste")
			(net "M_M_MA<3>")
		)
		(pad "72" smd rect
			(at 0 60.349892 270)
			(size 1.8034 0.508)
			(layers "B.Cu" "B.Mask" "B.Paste")
			(net "M_M_MA<1>")
		)
		(pad "73" smd rect
			(at 0 61.20003 270)
			(size 1.8034 0.508)
			(layers "B.Cu" "B.Mask" "B.Paste")
			(net "PVDDQ_KLM")
		)
		(pad "74" smd rect
			(at 0 62.049914 270)
			(size 1.8034 0.508)
			(layers "B.Cu" "B.Mask" "B.Paste")
			(net "M_M_CLK_DP<2>")
		)
		(pad "75" smd rect
			(at 0 62.900052 270)
			(size 1.8034 0.508)
			(layers "B.Cu" "B.Mask" "B.Paste")
			(net "M_M_CLK_DN<2>")
		)
		(pad "76" smd rect
			(at 0 63.749936 270)
			(size 1.8034 0.508)
			(layers "B.Cu" "B.Mask" "B.Paste")
			(net "PVDDQ_KLM")
		)
		(pad "77" smd rect
			(at 0 64.600074 270)
			(size 1.8034 0.508)
			(layers "B.Cu" "B.Mask" "B.Paste")
			(net "PVTT_KLM")
		)
		(pad "78" smd rect
			(at 0 70.550024 270)
			(size 1.8034 0.508)
			(layers "B.Cu" "B.Mask" "B.Paste")
			(net "FM_DIMM_EVENT_COD_N")
		)
		(pad "79" smd rect
			(at 0 71.399908 270)
			(size 1.8034 0.508)
			(layers "B.Cu" "B.Mask" "B.Paste")
			(net "M_M_MA<0>")
		)
		(pad "80" smd rect
			(at 0 72.250046 270)
			(size 1.8034 0.508)
			(layers "B.Cu" "B.Mask" "B.Paste")
			(net "PVDDQ_KLM")
		)
		(pad "81" smd rect
			(at 0 73.09993 270)
			(size 1.8034 0.508)
			(layers "B.Cu" "B.Mask" "B.Paste")
			(net "M_M_BA<0>")
		)
		(pad "82" smd rect
			(at 0 73.950068 270)
			(size 1.8034 0.508)
			(layers "B.Cu" "B.Mask" "B.Paste")
			(net "M_M_MA<16>")
		)
		(pad "83" smd rect
			(at 0 74.799952 270)
			(size 1.8034 0.508)
			(layers "B.Cu" "B.Mask" "B.Paste")
			(net "PVDDQ_KLM")
		)
		(pad "84" smd rect
			(at 0 75.65009 270)
			(size 1.8034 0.508)
			(layers "B.Cu" "B.Mask" "B.Paste")
			(net "M_M_CS_N<4>")
		)
		(pad "85" smd rect
			(at 0 76.499974 270)
			(size 1.8034 0.508)
			(layers "B.Cu" "B.Mask" "B.Paste")
			(net "PVDDQ_KLM")
		)
		(pad "86" smd rect
			(at 0 77.350112 270)
			(size 1.8034 0.508)
			(layers "B.Cu" "B.Mask" "B.Paste")
			(net "M_M_MA<15>")
		)
		(pad "87" smd rect
			(at 0 78.199996 270)
			(size 1.8034 0.508)
			(layers "B.Cu" "B.Mask" "B.Paste")
			(net "M_M_ODT<2>")
		)
		(pad "88" smd rect
			(at 0 79.04988 270)
			(size 1.8034 0.508)
			(layers "B.Cu" "B.Mask" "B.Paste")
			(net "PVDDQ_KLM")
		)
		(pad "89" smd rect
			(at 0 79.900018 270)
			(size 1.8034 0.508)
			(layers "B.Cu" "B.Mask" "B.Paste")
			(net "M_M_CS_N<5>")
		)
		(pad "90" smd rect
			(at 0 80.749902 270)
			(size 1.8034 0.508)
			(layers "B.Cu" "B.Mask" "B.Paste")
			(net "PVDDQ_KLM")
		)
		(pad "91" smd rect
			(at 0 81.60004 270)
			(size 1.8034 0.508)
			(layers "B.Cu" "B.Mask" "B.Paste")
			(net "M_M_ODT<3>")
		)
		(pad "92" smd rect
			(at 0 82.449924 270)
			(size 1.8034 0.508)
			(layers "B.Cu" "B.Mask" "B.Paste")
			(net "PVDDQ_KLM")
		)
		(pad "93" smd rect
			(at 0 83.300062 270)
			(size 1.8034 0.508)
			(layers "B.Cu" "B.Mask" "B.Paste")
			(net "M_M_CS_N<6>")
		)
		(pad "94" smd rect
			(at 0 84.149946 270)
			(size 1.8034 0.508)
			(layers "B.Cu" "B.Mask" "B.Paste")
			(net "GND")
		)
		(pad "95" smd rect
			(at 0 85.000084 270)
			(size 1.8034 0.508)
			(layers "B.Cu" "B.Mask" "B.Paste")
			(net "M_M_DQ<36>")
		)
		(pad "96" smd rect
			(at 0 85.849968 270)
			(size 1.8034 0.508)
			(layers "B.Cu" "B.Mask" "B.Paste")
			(net "GND")
		)
		(pad "97" smd rect
			(at 0 86.700106 270)
			(size 1.8034 0.508)
			(layers "B.Cu" "B.Mask" "B.Paste")
			(net "M_M_DQ<32>")
		)
	)
)
